#ISCELL
  mstr_misc dns *
  *
#ISCELL
  mstr_symbols intel_corp_bpage *
  *
#ISCELL
  mstr_standard offpage *
  page236_i1
#CELL
  mstr_discrete inductor *
  page236_i10
#ISCELL
  mstr_symbols gnd *
  page236_i11
#CELL
  mstr_discrete ir354xx *
  page236_i116
#CELL
  mstr_discrete ir354xx *
  page236_i117
#CELL
  mstr_discrete res *
  page236_i118
#ISCELL
  mstr_symbols gnd *
  page236_i119
#CELL
  mstr_discrete res *
  page236_i120
#ISCELL
  mstr_symbols gnd *
  page236_i121
#ISCELL
  mstr_symbols p5v_stby *
  page236_i122
#CELL
  dev_discrete cap_a *
  page236_i124
#ISCELL
  mstr_symbols gnd *
  page236_i125
#ISCELL
  mstr_symbols gnd *
  page236_i126
#CELL
  dev_discrete cap_a *
  page236_i127
#ISCELL
  mstr_symbols gnd *
  page236_i130
#CELL
  w_hdl sc2k2p50v3kx-gp *
  page236_i131
#CELL
  w_hdl 3d01r5f-gp *
  page236_i132
#ISCELL
  mstr_symbols gnd *
  page236_i133
#CELL
  mstr_discrete cap *
  page236_i134
#ISCELL
  mstr_symbols gnd *
  page236_i135
#CELL
  mstr_discrete cap *
  page236_i136
#CELL
  w_hdl 3d01r5f-gp *
  page236_i137
#ISCELL
  mstr_symbols gnd *
  page236_i139
#CELL
  mstr_discrete res *
  page236_i14
#CELL
  w_hdl sc2k2p50v3kx-gp *
  page236_i140
#CELL
  mstr_discrete res *
  page236_i141
#CELL
  mstr_discrete res *
  page236_i142
#CELL
  mstr_discrete cap *
  page236_i16
#CELL
  dev_discrete cap_a *
  page236_i17
#CELL
  mstr_discrete cap *
  page236_i19
#ISCELL
  mstr_standard offpage *
  page236_i2
#CELL
  dev_discrete cap_a *
  page236_i20
#CELL
  mstr_discrete cap *
  page236_i21
#CELL
  mstr_discrete cap *
  page236_i22
#CELL
  mstr_discrete cap *
  page236_i23
#CELL
  mstr_discrete cap *
  page236_i24
#ISCELL
  mstr_standard offpage *
  page236_i25
#CELL
  mstr_discrete cap *
  page236_i26
#ISCELL
  mstr_symbols gnd *
  page236_i27
#ISCELL
  mstr_symbols gnd *
  page236_i28
#CELL
  mstr_discrete cap *
  page236_i29
#ISCELL
  mstr_standard offpage *
  page236_i3
#ISCELL
  mstr_standard offpage *
  page236_i30
#CELL
  mstr_discrete cap *
  page236_i31
#CELL
  mstr_discrete cap *
  page236_i32
#CELL
  mstr_discrete cap *
  page236_i33
#CELL
  mstr_discrete cap *
  page236_i34
#CELL
  dev_discrete cap_a *
  page236_i35
#CELL
  mstr_discrete cap *
  page236_i36
#CELL
  dev_discrete cap_a *
  page236_i38
#CELL
  mstr_discrete cap *
  page236_i39
#CELL
  mstr_discrete res *
  page236_i41
#ISCELL
  mstr_symbols p5v_stby *
  page236_i42
#ISCELL
  mstr_symbols gnd *
  page236_i44
#CELL
  mstr_discrete inductor *
  page236_i45
#CELL
  mstr_discrete cap *
  page236_i46
#ISCELL
  mstr_symbols gnd *
  page236_i47
#ISCELL
  mstr_symbols p1v05_pch_stby *
  page236_i48
#ISCELL
  mstr_standard offpage *
  page236_i52
#ISCELL
  mstr_standard offpage *
  page236_i53
#ISCELL
  mstr_standard offpage *
  page236_i54
#ISCELL
  mstr_symbols p1v05_pch_stby *
  page236_i55
#CELL
  mstr_discrete res *
  page236_i56
#CELL
  mstr_discrete res *
  page236_i57
#ISCELL
  mstr_symbols gnd *
  page236_i58
#CELL
  mstr_discrete res *
  page236_i59
#ISCELL
  mstr_standard offpage *
  page236_i60
#ISCELL
  mstr_standard offpage *
  page236_i61
#CELL
  mstr_discrete cap *
  page236_i63
#ISCELL
  mstr_symbols gnd *
  page236_i64
#CELL
  mstr_discrete cap *
  page236_i65
#ISCELL
  mstr_symbols gnd *
  page236_i66
#ISCELL
  mstr_symbols pvnn_pch_stby *
  page236_i7
#CELL
  mstr_discrete capp *
  page236_i71
#CELL
  mstr_discrete capp *
  page236_i73
#CELL
  mstr_discrete capp *
  page236_i74
#CELL
  mstr_discrete capp *
  page236_i75
#CELL
  mstr_discrete capp *
  page236_i76
#CELL
  mstr_discrete capp *
  page236_i77
#CELL
  mstr_discrete capp *
  page236_i78
#CELL
  mstr_discrete capp *
  page236_i79
#ISCELL
  mstr_symbols gnd *
  page236_i8
#ISCELL
  mstr_symbols gnd *
  page236_i82
#ISCELL
  mstr_standard offpage *
  page236_i85
#ISCELL
  mstr_standard offpage *
  page236_i86
#ISCELL
  mstr_symbols pvnn_pch_stby *
  page236_i87
#ISCELL
  mstr_standard offpage *
  page236_i88
#ISCELL
  mstr_standard offpage *
  page236_i89
#CELL
  mstr_discrete cap *
  page236_i9
#CELL
  mstr_discrete res *
  page236_i90
#CELL
  mstr_discrete res *
  page236_i92
#CELL
  mstr_discrete res *
  page236_i93
#CELL
  mstr_discrete res *
  page236_i94
#ISCELL
  mstr_symbols vcc_core *
  page236_i95
#ISCELL
  mstr_symbols vcc_core *
  page236_i96
#ISCELL
  mstr_symbols vcc_core *
  page236_i97
